(kicad_pcb
	(version 20260206)
	(generator "pcbnew")
	(generator_version "10.0")
	(general
		(thickness 1.6)
		(legacy_teardrops no)
	)
	(paper "A4")
	(title_block
		(title "Bryce Canyon_IOM_IOC_16318-2_OCP.brd")
		(comment 1 "Bryce Canyon / footprints 1477-1484 of 1605")
	)
	(layers
		(0 "F.Cu" signal "TOP")
		(4 "In1.Cu" signal "L2GND")
		(6 "In2.Cu" signal "L3")
		(8 "In3.Cu" signal "L4VCC")
		(10 "In4.Cu" signal "L5VCC")
		(12 "In5.Cu" signal "L6")
		(14 "In6.Cu" signal "L7GND")
		(2 "B.Cu" signal "BOTTOM")
		(9 "F.Adhes" user "F.Adhesive")
		(11 "B.Adhes" user "B.Adhesive")
		(13 "F.Paste" user "Package Geometry/Pastemask Top")
		(15 "B.Paste" user "Package Geometry/Pastemask Bottom")
		(5 "F.SilkS" user "Ref Des/Silkscreen Top")
		(7 "B.SilkS" user "Ref Des/Silkscreen Bottom")
		(1 "F.Mask" user "Board Geometry/Soldermask Top")
		(3 "B.Mask" user "Board Geometry/Soldermask Bottom")
		(17 "Dwgs.User" user "User.Drawings")
		(19 "Cmts.User" user "User.Comments")
		(21 "Eco1.User" user "User.Eco1")
		(23 "Eco2.User" user "User.Eco2")
		(25 "Edge.Cuts" user "Board Geometry/Outline")
		(27 "Margin" user)
		(31 "F.CrtYd" user "Package Geometry/Place Bound Top")
		(29 "B.CrtYd" user "Package Geometry/Place Bound Bottom")
		(35 "F.Fab" user "Ref Des/Assembly Top")
		(33 "B.Fab" user "Ref Des/Assembly Bottom")
	)
	(footprint ""
		(layer "B.Cu")
		(at 67.31127 -139.596876 -90)
		(property "Reference" "C27"
			(at 0 0 90)
			(layer "B.SilkS")
			(hide yes)
			(effects
				(font
					(size 1.27 1.27)
				)
				(justify mirror)
			)
		)
		(property "Value" "SCD1U16V2KX-3GP"
			(at -1.1811 -2.7051 270)
			(unlocked yes)
			(layer "B.Fab")
			(hide yes)
			(effects
				(font
					(size 1.016 1.016)
					(thickness 0.1524)
				)
				(justify mirror)
			)
		)
		(property "Device Type" "C402H22"
			(at -1.1811 -4.2291 270)
			(unlocked yes)
			(layer "B.Fab")
			(hide yes)
			(effects
				(font
					(size 1.016 1.016)
					(thickness 0.1524)
				)
				(justify mirror)
			)
		)
		(duplicate_pad_numbers_are_jumpers no)
		(fp_rect
			(start 0.4318 0.9525)
			(end -0.4318 -0.9525)
			(stroke
				(width 0)
				(type default)
			)
			(fill no)
			(layer "B.CrtYd")
		)
		(fp_rect
			(start 0.4318 0.9525)
			(end -0.4318 -0.9525)
			(stroke
				(width 0)
				(type default)
			)
			(fill no)
			(layer "B.Fab")
		)
		(pad "1" smd custom
			(at 0 -0.4445 90)
			(size 0.1524 0.1524)
			(layers "B.Cu" "B.Mask" "B.Paste")
			(net "P3V3_STBY")
			(options
				(clearance outline)
				(anchor circle)
			)
			(primitives
				(gr_poly
					(pts
						(arc
							(start 0.3048 0.2032)
							(mid 0.275042 0.275042)
							(end 0.2032 0.3048)
						)
						(arc
							(start -0.2032 0.3048)
							(mid -0.275042 0.275042)
							(end -0.3048 0.2032)
						)
						(arc
							(start -0.3048 -0.2032)
							(mid -0.275042 -0.275042)
							(end -0.2032 -0.3048)
						)
						(arc
							(start 0.2032 -0.3048)
							(mid 0.275042 -0.275042)
							(end 0.3048 -0.2032)
						)
					)
					(width 0)
					(fill yes)
				)
			)
		)
		(pad "2" smd custom
			(at 0 0.4445 90)
			(size 0.1524 0.1524)
			(layers "B.Cu" "B.Mask" "B.Paste")
			(net "GND")
			(options
				(clearance outline)
				(anchor circle)
			)
			(primitives
				(gr_poly
					(pts
						(arc
							(start 0.3048 0.2032)
							(mid 0.275042 0.275042)
							(end 0.2032 0.3048)
						)
						(arc
							(start -0.2032 0.3048)
							(mid -0.275042 0.275042)
							(end -0.3048 0.2032)
						)
						(arc
							(start -0.3048 -0.2032)
							(mid -0.275042 -0.275042)
							(end -0.2032 -0.3048)
						)
						(arc
							(start 0.2032 -0.3048)
							(mid 0.275042 -0.275042)
							(end 0.3048 -0.2032)
						)
					)
					(width 0)
					(fill yes)
				)
			)
		)
	)
	(footprint ""
		(layer "B.Cu")
		(at 200.4314 -56.9976 -90)
		(property "Reference" "C441"
			(at 0 0 90)
			(layer "B.SilkS")
			(hide yes)
			(effects
				(font
					(size 1.27 1.27)
				)
				(justify mirror)
			)
		)
		(property "Value" "SCD1U16V2KX-3GP"
			(at -1.1811 -2.7051 270)
			(unlocked yes)
			(layer "B.Fab")
			(hide yes)
			(effects
				(font
					(size 1.016 1.016)
					(thickness 0.1524)
				)
				(justify mirror)
			)
		)
		(property "Device Type" "C402H22"
			(at -1.1811 -4.2291 270)
			(unlocked yes)
			(layer "B.Fab")
			(hide yes)
			(effects
				(font
					(size 1.016 1.016)
					(thickness 0.1524)
				)
				(justify mirror)
			)
		)
		(duplicate_pad_numbers_are_jumpers no)
		(fp_rect
			(start 0.4318 0.9525)
			(end -0.4318 -0.9525)
			(stroke
				(width 0)
				(type default)
			)
			(fill no)
			(layer "B.CrtYd")
		)
		(fp_rect
			(start 0.4318 0.9525)
			(end -0.4318 -0.9525)
			(stroke
				(width 0)
				(type default)
			)
			(fill no)
			(layer "B.Fab")
		)
		(pad "1" smd custom
			(at 0 -0.4445 90)
			(size 0.1524 0.1524)
			(layers "B.Cu" "B.Mask" "B.Paste")
			(net "P1V8")
			(options
				(clearance outline)
				(anchor circle)
			)
			(primitives
				(gr_poly
					(pts
						(arc
							(start 0.3048 0.2032)
							(mid 0.275042 0.275042)
							(end 0.2032 0.3048)
						)
						(arc
							(start -0.2032 0.3048)
							(mid -0.275042 0.275042)
							(end -0.3048 0.2032)
						)
						(arc
							(start -0.3048 -0.2032)
							(mid -0.275042 -0.275042)
							(end -0.2032 -0.3048)
						)
						(arc
							(start 0.2032 -0.3048)
							(mid 0.275042 -0.275042)
							(end 0.3048 -0.2032)
						)
					)
					(width 0)
					(fill yes)
				)
			)
		)
		(pad "2" smd custom
			(at 0 0.4445 90)
			(size 0.1524 0.1524)
			(layers "B.Cu" "B.Mask" "B.Paste")
			(net "GND")
			(options
				(clearance outline)
				(anchor circle)
			)
			(primitives
				(gr_poly
					(pts
						(arc
							(start 0.3048 0.2032)
							(mid 0.275042 0.275042)
							(end 0.2032 0.3048)
						)
						(arc
							(start -0.2032 0.3048)
							(mid -0.275042 0.275042)
							(end -0.3048 0.2032)
						)
						(arc
							(start -0.3048 -0.2032)
							(mid -0.275042 -0.275042)
							(end -0.2032 -0.3048)
						)
						(arc
							(start 0.2032 -0.3048)
							(mid 0.275042 -0.275042)
							(end 0.3048 -0.2032)
						)
					)
					(width 0)
					(fill yes)
				)
			)
		)
	)
	(footprint ""
		(layer "B.Cu")
		(at 50.4444 -135.763 180)
		(property "Reference" "R291"
			(at 0 0 0)
			(layer "B.SilkS")
			(hide yes)
			(effects
				(font
					(size 1.27 1.27)
				)
				(justify mirror)
			)
		)
		(property "Value" "0R2J-2-GP"
			(at -0.064008 -3.993896 180)
			(unlocked yes)
			(layer "B.Fab")
			(hide yes)
			(effects
				(font
					(size 1.016 1.016)
					(thickness 0.1524)
				)
				(justify mirror)
			)
		)
		(property "Device Type" "R402H16"
			(at -0.064008 -5.517896 180)
			(unlocked yes)
			(layer "B.Fab")
			(hide yes)
			(effects
				(font
					(size 1.016 1.016)
					(thickness 0.1524)
				)
				(justify mirror)
			)
		)
		(duplicate_pad_numbers_are_jumpers no)
		(fp_line
			(start 0.508 -0.9398)
			(end 0.508 0.9398)
			(stroke
				(width 0.1524)
				(type default)
			)
			(layer "B.SilkS")
		)
		(fp_line
			(start -0.508 -0.9398)
			(end 0.508 -0.9398)
			(stroke
				(width 0.1524)
				(type default)
			)
			(layer "B.SilkS")
		)
		(fp_rect
			(start 0.508 0.9398)
			(end -0.508 -0.9398)
			(stroke
				(width 0)
				(type default)
			)
			(fill no)
			(layer "B.CrtYd")
		)
		(fp_rect
			(start 0.508 0.9398)
			(end -0.508 -0.9398)
			(stroke
				(width 0)
				(type default)
			)
			(fill no)
			(layer "B.Fab")
		)
		(pad "1" smd custom
			(at 0 -0.4445)
			(size 0.1397 0.1397)
			(layers "B.Cu" "B.Mask" "B.Paste")
			(net "DPB_MISC_ALERT_OUT")
			(options
				(clearance outline)
				(anchor circle)
			)
			(primitives
				(gr_poly
					(pts
						(arc
							(start -0.1778 0.2794)
							(mid -0.249642 0.249642)
							(end -0.2794 0.1778)
						)
						(arc
							(start -0.2794 -0.1778)
							(mid -0.249642 -0.249642)
							(end -0.1778 -0.2794)
						)
						(arc
							(start 0.1778 -0.2794)
							(mid 0.249642 -0.249642)
							(end 0.2794 -0.1778)
						)
						(arc
							(start 0.2794 0.1778)
							(mid 0.249642 0.249642)
							(end 0.1778 0.2794)
						)
					)
					(width 0)
					(fill yes)
				)
			)
		)
		(pad "2" smd custom
			(at 0 0.4445)
			(size 0.1397 0.1397)
			(layers "B.Cu" "B.Mask" "B.Paste")
			(net "DPB_MISC_ALERT_O_R")
			(options
				(clearance outline)
				(anchor circle)
			)
			(primitives
				(gr_poly
					(pts
						(arc
							(start -0.1778 0.2794)
							(mid -0.249642 0.249642)
							(end -0.2794 0.1778)
						)
						(arc
							(start -0.2794 -0.1778)
							(mid -0.249642 -0.249642)
							(end -0.1778 -0.2794)
						)
						(arc
							(start 0.1778 -0.2794)
							(mid 0.249642 -0.249642)
							(end 0.2794 -0.1778)
						)
						(arc
							(start 0.2794 0.1778)
							(mid 0.249642 0.249642)
							(end 0.1778 0.2794)
						)
					)
					(width 0)
					(fill yes)
				)
			)
		)
	)
	(footprint ""
		(layer "B.Cu")
		(at 79.826866 -58.205878 90)
		(property "Reference" "C188"
			(at 0 0 90)
			(layer "B.SilkS")
			(hide yes)
			(effects
				(font
					(size 1.27 1.27)
				)
				(justify mirror)
			)
		)
		(property "Value" "SC10U6D3V5KX-4GP"
			(at 0.0762 -6.1214 90)
			(unlocked yes)
			(layer "B.Fab")
			(hide yes)
			(effects
				(font
					(size 1.016 1.016)
					(thickness 0.1524)
				)
				(justify mirror)
			)
		)
		(property "Device Type" "C805H58"
			(at 0.0762 -8.1534 90)
			(unlocked yes)
			(layer "B.Fab")
			(hide yes)
			(effects
				(font
					(size 1.016 1.016)
					(thickness 0.1524)
				)
				(justify mirror)
			)
		)
		(duplicate_pad_numbers_are_jumpers no)
		(fp_line
			(start -0.635 0)
			(end 0.635 0)
			(stroke
				(width 0.508)
				(type default)
			)
			(layer "B.SilkS")
		)
		(fp_rect
			(start 0.9652 1.778)
			(end -0.9652 -1.778)
			(stroke
				(width 0)
				(type default)
			)
			(fill no)
			(layer "B.CrtYd")
		)
		(fp_poly
			(pts
				(xy 0.9652 -1.778) (xy -0.9652 -1.778) (xy -0.9652 1.778) (xy 0.9652 1.778)
			)
			(stroke
				(width 0)
				(type default)
			)
			(fill no)
			(layer "B.Fab")
		)
		(pad "1" smd rect
			(at 0 -0.9652 270)
			(size 1.397 1.143)
			(layers "B.Cu" "B.Mask" "B.Paste")
			(net "P3V3")
		)
		(pad "2" smd rect
			(at 0 0.9652 270)
			(size 1.397 1.143)
			(layers "B.Cu" "B.Mask" "B.Paste")
			(net "GND")
		)
	)
	(footprint ""
		(layer "B.Cu")
		(at 62.996318 -144.769078 90)
		(property "Reference" "R202"
			(at 0 0 90)
			(layer "B.SilkS")
			(hide yes)
			(effects
				(font
					(size 1.27 1.27)
				)
				(justify mirror)
			)
		)
		(property "Value" "2K2R2F-GP"
			(at -0.064008 -3.993896 90)
			(unlocked yes)
			(layer "B.Fab")
			(hide yes)
			(effects
				(font
					(size 1.016 1.016)
					(thickness 0.1524)
				)
				(justify mirror)
			)
		)
		(property "Device Type" "R402H16"
			(at -0.064008 -5.517896 90)
			(unlocked yes)
			(layer "B.Fab")
			(hide yes)
			(effects
				(font
					(size 1.016 1.016)
					(thickness 0.1524)
				)
				(justify mirror)
			)
		)
		(duplicate_pad_numbers_are_jumpers no)
		(fp_line
			(start 0.508 -0.9398)
			(end 0.508 0.9398)
			(stroke
				(width 0.1524)
				(type default)
			)
			(layer "B.SilkS")
		)
		(fp_line
			(start -0.508 -0.9398)
			(end 0.508 -0.9398)
			(stroke
				(width 0.1524)
				(type default)
			)
			(layer "B.SilkS")
		)
		(fp_rect
			(start 0.508 0.9398)
			(end -0.508 -0.9398)
			(stroke
				(width 0)
				(type default)
			)
			(fill no)
			(layer "B.CrtYd")
		)
		(fp_rect
			(start 0.508 0.9398)
			(end -0.508 -0.9398)
			(stroke
				(width 0)
				(type default)
			)
			(fill no)
			(layer "B.Fab")
		)
		(pad "1" smd custom
			(at 0 -0.4445 270)
			(size 0.1397 0.1397)
			(layers "B.Cu" "B.Mask" "B.Paste")
			(net "I2C_MEZZ_FRU_SENSOR_SDA")
			(options
				(clearance outline)
				(anchor circle)
			)
			(primitives
				(gr_poly
					(pts
						(arc
							(start -0.1778 0.2794)
							(mid -0.249642 0.249642)
							(end -0.2794 0.1778)
						)
						(arc
							(start -0.2794 -0.1778)
							(mid -0.249642 -0.249642)
							(end -0.1778 -0.2794)
						)
						(arc
							(start 0.1778 -0.2794)
							(mid 0.249642 -0.249642)
							(end 0.2794 -0.1778)
						)
						(arc
							(start 0.2794 0.1778)
							(mid 0.249642 0.249642)
							(end 0.1778 0.2794)
						)
					)
					(width 0)
					(fill yes)
				)
			)
		)
		(pad "2" smd custom
			(at 0 0.4445 270)
			(size 0.1397 0.1397)
			(layers "B.Cu" "B.Mask" "B.Paste")
			(net "P3V3_STBY")
			(options
				(clearance outline)
				(anchor circle)
			)
			(primitives
				(gr_poly
					(pts
						(arc
							(start -0.1778 0.2794)
							(mid -0.249642 0.249642)
							(end -0.2794 0.1778)
						)
						(arc
							(start -0.2794 -0.1778)
							(mid -0.249642 -0.249642)
							(end -0.1778 -0.2794)
						)
						(arc
							(start 0.1778 -0.2794)
							(mid 0.249642 -0.249642)
							(end 0.2794 -0.1778)
						)
						(arc
							(start 0.2794 0.1778)
							(mid 0.249642 0.249642)
							(end 0.1778 0.2794)
						)
					)
					(width 0)
					(fill yes)
				)
			)
		)
	)
	(footprint ""
		(layer "B.Cu")
		(at 192.405 -62.1792 90)
		(property "Reference" "C410"
			(at 0 0 90)
			(layer "B.SilkS")
			(hide yes)
			(effects
				(font
					(size 1.27 1.27)
				)
				(justify mirror)
			)
		)
		(property "Value" "SCD1U6D3V1KX-GP"
			(at 2.8321 -1.7399 90)
			(unlocked yes)
			(layer "B.Fab")
			(hide yes)
			(effects
				(font
					(size 1.016 1.016)
					(thickness 0.1524)
				)
				(justify mirror)
			)
		)
		(property "Device Type" "C0201H13"
			(at 2.8321 -3.2639 90)
			(unlocked yes)
			(layer "B.Fab")
			(hide yes)
			(effects
				(font
					(size 1.016 1.016)
					(thickness 0.1524)
				)
				(justify mirror)
			)
		)
		(duplicate_pad_numbers_are_jumpers no)
		(fp_rect
			(start 0.2794 0.6477)
			(end -0.2794 -0.6477)
			(stroke
				(width 0)
				(type default)
			)
			(fill no)
			(layer "B.CrtYd")
		)
		(fp_rect
			(start 0.2794 0.6477)
			(end -0.2794 -0.6477)
			(stroke
				(width 0)
				(type default)
			)
			(fill no)
			(layer "B.Fab")
		)
		(pad "1" smd custom
			(at 0 -0.2794 270)
			(size 0.0762 0.0762)
			(layers "B.Cu" "B.Mask" "B.Paste")
			(net "P0V975")
			(options
				(clearance outline)
				(anchor circle)
			)
			(primitives
				(gr_poly
					(pts
						(arc
							(start 0.1524 0.127)
							(mid 0.137521 0.162921)
							(end 0.1016 0.1778)
						)
						(arc
							(start -0.1016 0.1778)
							(mid -0.137521 0.162921)
							(end -0.1524 0.127)
						)
						(arc
							(start -0.1524 -0.127)
							(mid -0.137521 -0.162921)
							(end -0.1016 -0.1778)
						)
						(arc
							(start 0.1016 -0.1778)
							(mid 0.137521 -0.162921)
							(end 0.1524 -0.127)
						)
					)
					(width 0)
					(fill yes)
				)
			)
		)
		(pad "2" smd custom
			(at 0 0.2794 270)
			(size 0.0762 0.0762)
			(layers "B.Cu" "B.Mask" "B.Paste")
			(net "GND")
			(options
				(clearance outline)
				(anchor circle)
			)
			(primitives
				(gr_poly
					(pts
						(arc
							(start 0.1524 0.127)
							(mid 0.137521 0.162921)
							(end 0.1016 0.1778)
						)
						(arc
							(start -0.1016 0.1778)
							(mid -0.137521 0.162921)
							(end -0.1524 0.127)
						)
						(arc
							(start -0.1524 -0.127)
							(mid -0.137521 -0.162921)
							(end -0.1016 -0.1778)
						)
						(arc
							(start 0.1016 -0.1778)
							(mid 0.137521 -0.162921)
							(end 0.1524 -0.127)
						)
					)
					(width 0)
					(fill yes)
				)
			)
		)
	)
	(footprint ""
		(layer "B.Cu")
		(at 61.4934 -148.5138 180)
		(property "Reference" "R389"
			(at 0 0 0)
			(layer "B.SilkS")
			(hide yes)
			(effects
				(font
					(size 1.27 1.27)
				)
				(justify mirror)
			)
		)
		(property "Value" "4K7R2F-GP"
			(at -0.064008 -3.993896 180)
			(unlocked yes)
			(layer "B.Fab")
			(hide yes)
			(effects
				(font
					(size 1.016 1.016)
					(thickness 0.1524)
				)
				(justify mirror)
			)
		)
		(property "Device Type" "R402H16"
			(at -0.064008 -5.517896 180)
			(unlocked yes)
			(layer "B.Fab")
			(hide yes)
			(effects
				(font
					(size 1.016 1.016)
					(thickness 0.1524)
				)
				(justify mirror)
			)
		)
		(duplicate_pad_numbers_are_jumpers no)
		(fp_line
			(start 0.508 -0.9398)
			(end 0.508 0.9398)
			(stroke
				(width 0.1524)
				(type default)
			)
			(layer "B.SilkS")
		)
		(fp_line
			(start -0.508 -0.9398)
			(end 0.508 -0.9398)
			(stroke
				(width 0.1524)
				(type default)
			)
			(layer "B.SilkS")
		)
		(fp_rect
			(start 0.508 0.9398)
			(end -0.508 -0.9398)
			(stroke
				(width 0)
				(type default)
			)
			(fill no)
			(layer "B.CrtYd")
		)
		(fp_rect
			(start 0.508 0.9398)
			(end -0.508 -0.9398)
			(stroke
				(width 0)
				(type default)
			)
			(fill no)
			(layer "B.Fab")
		)
		(pad "1" smd custom
			(at 0 -0.4445)
			(size 0.1397 0.1397)
			(layers "B.Cu" "B.Mask" "B.Paste")
			(net "GND")
			(options
				(clearance outline)
				(anchor circle)
			)
			(primitives
				(gr_poly
					(pts
						(arc
							(start -0.1778 0.2794)
							(mid -0.249642 0.249642)
							(end -0.2794 0.1778)
						)
						(arc
							(start -0.2794 -0.1778)
							(mid -0.249642 -0.249642)
							(end -0.1778 -0.2794)
						)
						(arc
							(start 0.1778 -0.2794)
							(mid 0.249642 -0.249642)
							(end 0.2794 -0.1778)
						)
						(arc
							(start 0.2794 0.1778)
							(mid 0.249642 0.249642)
							(end 0.1778 0.2794)
						)
					)
					(width 0)
					(fill yes)
				)
			)
		)
		(pad "2" smd custom
			(at 0 0.4445)
			(size 0.1397 0.1397)
			(layers "B.Cu" "B.Mask" "B.Paste")
			(net "MAC1_TXD3")
			(options
				(clearance outline)
				(anchor circle)
			)
			(primitives
				(gr_poly
					(pts
						(arc
							(start -0.1778 0.2794)
							(mid -0.249642 0.249642)
							(end -0.2794 0.1778)
						)
						(arc
							(start -0.2794 -0.1778)
							(mid -0.249642 -0.249642)
							(end -0.1778 -0.2794)
						)
						(arc
							(start 0.1778 -0.2794)
							(mid 0.249642 -0.249642)
							(end 0.2794 -0.1778)
						)
						(arc
							(start 0.2794 0.1778)
							(mid 0.249642 0.249642)
							(end 0.1778 0.2794)
						)
					)
					(width 0)
					(fill yes)
				)
			)
		)
	)
	(footprint ""
		(layer "B.Cu")
		(at 80.6196 -130.048 -90)
		(property "Reference" "U103"
			(at 0 0 90)
			(layer "B.SilkS")
			(hide yes)
			(effects
				(font
					(size 1.27 1.27)
				)
				(justify mirror)
			)
		)
		(property "Value" "SNLVC1G126DCKR-GP"
			(at 2.3368 -8.6868 270)
			(unlocked yes)
			(layer "B.Fab")
			(hide yes)
			(effects
				(font
					(size 1.016 1.016)
					(thickness 0.1524)
				)
				(justify mirror)
			)
		)
		(property "Device Type" "SC70-5H44"
			(at 2.3114 -10.414 270)
			(unlocked yes)
			(layer "B.Fab")
			(hide yes)
			(effects
				(font
					(size 1.016 1.016)
					(thickness 0.1524)
				)
				(justify mirror)
			)
		)
		(duplicate_pad_numbers_are_jumpers no)
		(fp_line
			(start -1.27 1.7018)
			(end 1.27 1.7018)
			(stroke
				(width 0.1524)
				(type default)
			)
			(layer "B.SilkS")
		)
		(fp_line
			(start 1.27 1.7018)
			(end 1.27 -1.7018)
			(stroke
				(width 0.1524)
				(type default)
			)
			(layer "B.SilkS")
		)
		(fp_line
			(start -1.27 -1.7018)
			(end -1.27 1.7018)
			(stroke
				(width 0.1524)
				(type default)
			)
			(layer "B.SilkS")
		)
		(fp_line
			(start 1.27 -1.7018)
			(end -1.27 -1.7018)
			(stroke
				(width 0.1524)
				(type default)
			)
			(layer "B.SilkS")
		)
		(fp_line
			(start -1.3843 -1.8034)
			(end -1.3843 -1.1176)
			(stroke
				(width 0.3302)
				(type default)
			)
			(layer "B.SilkS")
		)
		(fp_line
			(start -0.6604 -1.8034)
			(end -1.3843 -1.8034)
			(stroke
				(width 0.3302)
				(type default)
			)
			(layer "B.SilkS")
		)
		(fp_rect
			(start 1.524 1.9558)
			(end -1.524 -1.9558)
			(stroke
				(width 0)
				(type default)
			)
			(fill no)
			(layer "B.CrtYd")
		)
		(fp_poly
			(pts
				(xy 1.524 -1.9558) (xy -1.524 -1.9558) (xy -1.524 1.9558) (xy 1.524 1.9558)
			)
			(stroke
				(width 0)
				(type default)
			)
			(fill no)
			(layer "B.Fab")
		)
		(pad "1" smd rect
			(at -0.65024 -0.8255 90)
			(size 0.4064 1.2192)
			(layers "B.Cu" "B.Mask" "B.Paste")
			(net "PWRGD_P3V3_STBY")
		)
		(pad "2" smd rect
			(at 0 -0.8255 90)
			(size 0.4064 1.2192)
			(layers "B.Cu" "B.Mask" "B.Paste")
			(net "BMC_TO_EXP_RESET_OUT_R")
		)
		(pad "3" smd rect
			(at 0.65024 -0.8255 90)
			(size 0.4064 1.2192)
			(layers "B.Cu" "B.Mask" "B.Paste")
			(net "GND")
		)
		(pad "4" smd rect
			(at 0.65024 0.8255 90)
			(size 0.4064 1.2192)
			(layers "B.Cu" "B.Mask" "B.Paste")
			(net "BMC_TO_EXP_RESET_N")
		)
		(pad "5" smd rect
			(at -0.65024 0.8255 90)
			(size 0.4064 1.2192)
			(layers "B.Cu" "B.Mask" "B.Paste")
			(net "P3V3_STBY")
		)
	)
)
